# S9S_MB_2U (Grand Teton) — schematic parts with pin connectivity, parts 5154–5288 of 6093; source: Cadence DE-HDL packaged netlist (pstxprt.dat, pstxnet.dat, pstchip.dat)

R3751  Q_RES  0 5% CHIP  pkg 0402LF  page 171 : 1 = INA230_2_A0 ; 2 = SMB_INA230_2_3V3AUX_SDA_R1
R3752  Q_RES  0 5% CHIP  pkg 0402LF  page 171 : 1 = E1S_0_P3V3_ADC_ALERT_R ; 2 = E1S_0_P3V3_ADC_ALERT
R3754  Q_RES  33.2 1% CHIP  pkg 0402LF  page 171 : 1 = SMB_INA230_2_3V3AUX_SCL_R ; 2 = SMB_INA230_2_3V3AUX_SCL_R1
R3756  Q_RES  33.2 1% CHIP  pkg 0402LF  page 171 : 1 = SMB_INA230_2_3V3AUX_SDA_R ; 2 = SMB_INA230_2_3V3AUX_SDA_R1
R3758  Q_RES  10 1% CHIP  pkg 0402LF  page 171 : 1 = P3V3_E1S_0_R ; 2 = VSENSE_P3V3_INA230_2_INP
R3760  Q_RES  10 1% CHIP  pkg 0402LF  page 171 : 1 = P3V3_E1S_0 ; 2 = VSENSE_P3V3_INA230_2_INN
R3763  Q_RES  4.7K 1% CHIP  pkg 0402LF  page 171 : 1 = GND ; 2 = INA230_2_A1
R3764  Q_RES  4.7K 1% EMPTY  pkg 0402LF  page 171 : 1 = GND ; 2 = INA230_2_A0
R3767  Q_RES  0.01 1% CHIP  pkg 2512LF  page 171 : 1 = P3V3_E1S_0 ; 2 = P3V3_E1S_0_R
R3770  Q_RES  0 5% CHIP  pkg 0402LF  page 246 : 1 = GPU_PRSNT ; 2 = GPU_PRSNT_R
R3771  Q_RES  10K 1% CHIP  pkg 0402LF  page 191 : 1 = P3V3_AUX ; 2 = E1S_0_PWRDIS
R3772  Q_RES  0 5% CHIP  pkg 0402LF  page 191 : 1 = RST_SMB_BUF_E1S_0_N ; 2 = RST_SMB_E1S_0_N
R3773  Q_RES  4.7K 5% EMPTY  pkg 0402LF  page 191 : 1 = P3V3_AUX ; 2 = RST_SMB_E1S_0_N
R3775  Q_RES  0 5% CHIP  pkg 0402LF  page 191 : 1 = RST_SMB_SWITCH_N ; 2 = RST_SMB_E1S_N
R3776  Q_RES  0 5% CHIP  pkg 0402LF  page 240 : 1 = FM_UARTSW_MSB_N ; 2 = FM_UARTSW_MSB_R
R3777  Q_RES  0 5% CHIP  pkg 0402LF  page 240 : 1 = FM_UARTSW_LSB_N ; 2 = FM_UARTSW_LSB_R
R3778  Q_RES  0 5% CHIP  pkg 0402LF  page 240 : 1 = FM_SOL_UART_CH_SEL_R ; 2 = FM_SOL_UART_CH_SEL
R3779  Q_RES  0 5% CHIP  pkg 0402LF  page 191 : 1 = RST_PCIE_PCH_DEV_PERST_E1S_R_N ; 2 = RST_PCIE_PCH_E1S_PERST_N
R3783  Q_RES  100K 1% CHIP  pkg 0402LF  page 156 : 1 = P3V3_AUX ; 2 = OCP_V3_1_P3V3_PWRGD
R3784  Q_RES  0 5% EMPTY  pkg 0402LF  page 156 : 1 = P12V_OCP_UV_1_R ; 2 = P12V_OCP_UV_1
R3785  Q_RES  0 5% CHIP  pkg 0402LF  page 156 : 1 = P3V3_OCP_UV_1_R1 ; 2 = P3V3_OCP_UV_1
R3794  Q_RES  0 5% CHIP  pkg 0402LF  page 156 : 1 = P3V3_OCP_PWRGD_1 ; 2 = OCP_V3_1_P3V3_PWRGD
R3796  Q_RES  100K 1% CHIP  pkg 0402LF  page 156 : 1 = P3V3_AUX ; 2 = P3V3_OCP_FAULT_1
R3797  Q_RES  100K 1% EMPTY  pkg 0402LF  page 156 : 1 = P3V3_AUX ; 2 = HP_LVC3_OCP_V3_1_P12V_PWRGD
R3799  Q_RES  100K 1% EMPTY  pkg 0402LF  page 156 : 1 = P3V3_AUX ; 2 = P12V_OCP_FAULT_1
R3807  Q_RES  0 5% CHIP  pkg 0402LF  page 162 : 1 = P3V3_OCP_UV_2_R1 ; 2 = P3V3_OCP_UV_2
R3816  Q_RES  100K 1% EMPTY  pkg 0402LF  page 162 : 1 = P3V3_AUX ; 2 = P12V_OCP_FAULT_2
R3825  Q_RES  100K 1% EMPTY  pkg 0402LF  page 162 : 1 = P3V3_AUX ; 2 = HP_LVC3_OCP_V3_2_P12V_PWRGD
R3826  Q_RES  100K 1% CHIP  pkg 0402LF  page 162 : 1 = P3V3_AUX ; 2 = OCP_V3_2_P3V3_PWRGD
R3827  Q_RES  0 5% EMPTY  pkg 0402LF  page 162 : 1 = P12V_OCP_UV_2_R ; 2 = P12V_OCP_UV_2
R3831  Q_RES  0 5% EMPTY  pkg 0402LF  page 162 : 1 = P12V_OCP_PWRGD_2 ; 2 = HP_LVC3_OCP_V3_2_P12V_PWRGD
R3832  Q_RES  0 5% CHIP  pkg 0402LF  page 162 : 1 = P3V3_OCP_PWRGD_2 ; 2 = OCP_V3_2_P3V3_PWRGD
R3833  Q_RES  100K 1% CHIP  pkg 0402LF  page 162 : 1 = P3V3_AUX ; 2 = P3V3_OCP_FAULT_2
R3834  Q_RES  0 5% CHIP  pkg 0402LF  page 157 : 1 = HP_LVC3_OCP_V3_1_EN ; 2 = P12V_OCP_EN_1_R2
R3836  Q_RES  10K 1% CHIP  pkg 0402LF  page 242 : 1 = P3V3_AUX ; 2 = HP_LVC3_SCM_HSC_PWRGD_R
R3845  Q_RES  0 5% EMPTY  pkg 0402LF  page 157 : 1 = HP_LVC3_OCP_V3_1_EN ; 2 = P3V3_OCP_EN_1_R2
R3848  Q_RES  10K 1% CHIP  pkg 0402LF  page 163 : 1 = P3V3_AUX ; 2 = HP_LVC3_OCP_V3_2_P12V_PWRGD
R3858  Q_RES  33.2 1% CHIP  pkg 0402LF  page 240 : 1 = SMB_OCP_V3_2_3V3AUX_SDA ; 2 = SMB_OCP_V3_2_3V3AUX_SDA_R0
R3859  Q_RES  0 5% EMPTY  pkg 0402LF  page 250 : 1 = P12V_OCP_V3_2_ISENSE_MAM_MAM ; 2 = P12V_OCP_V3_2_ISENSE_MAM
R3860  Q_RES  0 5% EMPTY  pkg 0402LF  page 250 : 1 = P12V_OCP_V3_2_ISENSE_MPS_MAM ; 2 = P12V_OCP_V3_2_ISENSE_MAM
R3861  Q_RES  0 5% EMPTY  pkg 0402LF  page 250 : 1 = P12V_OCP_V3_2_ISENSE_MAM_TIC ; 2 = P12V_OCP_V3_2_ISENSE_TIC
R3862  Q_RES  0 5% CHIP  pkg 0402LF  page 250 : 1 = P12V_OCP_V3_2_ISENSE_MPS_TIC ; 2 = P12V_OCP_V3_2_ISENSE_TIC
R3863  Q_RES  0 5% EMPTY  pkg 0402LF  page 250 : 1 = P12V_OCP_SFF_ISENSE_MAM_MAM ; 2 = P12V_OCP_SFF_ISENSE_MAM
R3864  Q_RES  0 5% EMPTY  pkg 0402LF  page 250 : 1 = P12V_OCP_SFF_ISENSE_MPS_MAM ; 2 = P12V_OCP_SFF_ISENSE_MAM
R3865  Q_RES  0 5% EMPTY  pkg 0402LF  page 250 : 1 = P12V_OCP_SFF_ISENSE_MAM_TIC ; 2 = P12V_OCP_SFF_ISENSE_TIC
R3866  Q_RES  0 5% CHIP  pkg 0402LF  page 250 : 1 = P12V_OCP_SFF_ISENSE_MPS_TIC ; 2 = P12V_OCP_SFF_ISENSE_TIC
R3867  Q_RES  0 5% EMPTY  pkg 0402LF  page 162 : 1 = P12V_OCP_SENSE_2 ; 2 = P12V_OCP_V3_2_ISENSE_MAM_MAM
R3868  Q_RES  0 5% EMPTY  pkg 0402LF  page 162 : 1 = P12V_OCP_SENSE_2 ; 2 = P12V_OCP_V3_2_ISENSE_MAM_TIC
R3869  Q_RES  0 5% EMPTY  pkg 0402LF  page 156 : 1 = P12V_OCP_SENSE_1 ; 2 = P12V_OCP_SFF_ISENSE_MAM_MAM
R3870  Q_RES  0 5% EMPTY  pkg 0402LF  page 156 : 1 = P12V_OCP_SENSE_1 ; 2 = P12V_OCP_SFF_ISENSE_MAM_TIC
R3871  Q_RES  0 5% EMPTY  pkg 0402LF  page 157 : 1 = P12V_OCP_IMON_1 ; 2 = P12V_OCP_SFF_ISENSE_MPS_MAM
R3872  Q_RES  0 5% CHIP  pkg 0402LF  page 157 : 1 = P12V_OCP_IMON_1 ; 2 = P12V_OCP_SFF_ISENSE_MPS_TIC
R3873  Q_RES  0 5% EMPTY  pkg 0402LF  page 163 : 1 = P12V_OCP_IMON_2 ; 2 = P12V_OCP_V3_2_ISENSE_MPS_MAM
R3874  Q_RES  0 5% CHIP  pkg 0402LF  page 163 : 1 = P12V_OCP_IMON_2 ; 2 = P12V_OCP_V3_2_ISENSE_MPS_TIC
R3875  Q_RES  49.9 1% CHIP  pkg 0402LF  page 82 : 1 = I3C_SPD_DDRABCD_CPU0_LVC1_SCL_R ; 2 = I3C_SPD_DDRABCD_CPU0_LVC1_SCL
R3876  Q_RES  49.9 1% CHIP  pkg 0402LF  page 83 : 1 = I3C_SPD_DDRABCD_CPU0_LVC1_SCL_1 ; 2 = I3C_SPD_DDRABCD_CPU0_LVC1_SCL
R3877  Q_RES  49.9 1% CHIP  pkg 0402LF  page 84 : 1 = I3C_SPD_DDRABCD_CPU0_LVC1_SCL_2 ; 2 = I3C_SPD_DDRABCD_CPU0_LVC1_SCL
R3878  Q_RES  49.9 1% CHIP  pkg 0402LF  page 85 : 1 = I3C_SPD_DDRABCD_CPU0_LVC1_SCL_3 ; 2 = I3C_SPD_DDRABCD_CPU0_LVC1_SCL
R3879  Q_RES  49.9 1% CHIP  pkg 0402LF  page 86 : 1 = I3C_SPD_DDRABCD_CPU0_LVC1_SCL_4 ; 2 = I3C_SPD_DDRABCD_CPU0_LVC1_SCL
R3880  Q_RES  49.9 1% CHIP  pkg 0402LF  page 87 : 1 = I3C_SPD_DDRABCD_CPU0_LVC1_SCL_5 ; 2 = I3C_SPD_DDRABCD_CPU0_LVC1_SCL
R3881  Q_RES  49.9 1% CHIP  pkg 0402LF  page 88 : 1 = I3C_SPD_DDRABCD_CPU0_LVC1_SCL_6 ; 2 = I3C_SPD_DDRABCD_CPU0_LVC1_SCL
R3882  Q_RES  49.9 1% CHIP  pkg 0402LF  page 89 : 1 = I3C_SPD_DDRABCD_CPU0_LVC1_SCL_7 ; 2 = I3C_SPD_DDRABCD_CPU0_LVC1_SCL
R3883  Q_RES  49.9 1% CHIP  pkg 0402LF  page 90 : 1 = I3C_SPD_DDREFGH_CPU0_LVC1_SCL_R ; 2 = I3C_SPD_DDREFGH_CPU0_LVC1_SCL
R3884  Q_RES  49.9 1% CHIP  pkg 0402LF  page 91 : 1 = I3C_SPD_DDREFGH_CPU0_LVC1_SCL_1 ; 2 = I3C_SPD_DDREFGH_CPU0_LVC1_SCL
R3885  Q_RES  49.9 1% CHIP  pkg 0402LF  page 92 : 1 = I3C_SPD_DDREFGH_CPU0_LVC1_SCL_2 ; 2 = I3C_SPD_DDREFGH_CPU0_LVC1_SCL
R3886  Q_RES  49.9 1% CHIP  pkg 0402LF  page 93 : 1 = I3C_SPD_DDREFGH_CPU0_LVC1_SCL_3 ; 2 = I3C_SPD_DDREFGH_CPU0_LVC1_SCL
R3887  Q_RES  49.9 1% CHIP  pkg 0402LF  page 94 : 1 = I3C_SPD_DDREFGH_CPU0_LVC1_SCL_4 ; 2 = I3C_SPD_DDREFGH_CPU0_LVC1_SCL
R3888  Q_RES  49.9 1% CHIP  pkg 0402LF  page 95 : 1 = I3C_SPD_DDREFGH_CPU0_LVC1_SCL_5 ; 2 = I3C_SPD_DDREFGH_CPU0_LVC1_SCL
R3889  Q_RES  49.9 1% CHIP  pkg 0402LF  page 96 : 1 = I3C_SPD_DDREFGH_CPU0_LVC1_SCL_6 ; 2 = I3C_SPD_DDREFGH_CPU0_LVC1_SCL
R3890  Q_RES  49.9 1% CHIP  pkg 0402LF  page 97 : 1 = I3C_SPD_DDREFGH_CPU0_LVC1_SCL_7 ; 2 = I3C_SPD_DDREFGH_CPU0_LVC1_SCL
R3891  Q_RES  49.9 1% CHIP  pkg 0402LF  page 98 : 1 = I3C_SPD_DDRABCD_CPU1_LVC1_SCL_R ; 2 = I3C_SPD_DDRABCD_CPU1_LVC1_SCL
R3892  Q_RES  49.9 1% CHIP  pkg 0402LF  page 99 : 1 = I3C_SPD_DDRABCD_CPU1_LVC1_SCL_1 ; 2 = I3C_SPD_DDRABCD_CPU1_LVC1_SCL
R3893  Q_RES  49.9 1% CHIP  pkg 0402LF  page 100 : 1 = I3C_SPD_DDRABCD_CPU1_LVC1_SCL_2 ; 2 = I3C_SPD_DDRABCD_CPU1_LVC1_SCL
R3894  Q_RES  49.9 1% CHIP  pkg 0402LF  page 101 : 1 = I3C_SPD_DDRABCD_CPU1_LVC1_SCL_3 ; 2 = I3C_SPD_DDRABCD_CPU1_LVC1_SCL
R3895  Q_RES  49.9 1% CHIP  pkg 0402LF  page 102 : 1 = I3C_SPD_DDRABCD_CPU1_LVC1_SCL_4 ; 2 = I3C_SPD_DDRABCD_CPU1_LVC1_SCL
R3896  Q_RES  49.9 1% CHIP  pkg 0402LF  page 103 : 1 = I3C_SPD_DDRABCD_CPU1_LVC1_SCL_5 ; 2 = I3C_SPD_DDRABCD_CPU1_LVC1_SCL
R3897  Q_RES  49.9 1% CHIP  pkg 0402LF  page 104 : 1 = I3C_SPD_DDRABCD_CPU1_LVC1_SCL_6 ; 2 = I3C_SPD_DDRABCD_CPU1_LVC1_SCL
R3898  Q_RES  49.9 1% CHIP  pkg 0402LF  page 105 : 1 = I3C_SPD_DDRABCD_CPU1_LVC1_SCL_7 ; 2 = I3C_SPD_DDRABCD_CPU1_LVC1_SCL
R3899  Q_RES  49.9 1% CHIP  pkg 0402LF  page 106 : 1 = I3C_SPD_DDREFGH_CPU1_LVC1_SCL_R ; 2 = I3C_SPD_DDREFGH_CPU1_LVC1_SCL
R3900  Q_RES  49.9 1% CHIP  pkg 0402LF  page 107 : 1 = I3C_SPD_DDREFGH_CPU1_LVC1_SCL_1 ; 2 = I3C_SPD_DDREFGH_CPU1_LVC1_SCL
R3901  Q_RES  49.9 1% CHIP  pkg 0402LF  page 108 : 1 = I3C_SPD_DDREFGH_CPU1_LVC1_SCL_2 ; 2 = I3C_SPD_DDREFGH_CPU1_LVC1_SCL
R3902  Q_RES  49.9 1% CHIP  pkg 0402LF  page 109 : 1 = I3C_SPD_DDREFGH_CPU1_LVC1_SCL_3 ; 2 = I3C_SPD_DDREFGH_CPU1_LVC1_SCL
R3903  Q_RES  49.9 1% CHIP  pkg 0402LF  page 110 : 1 = I3C_SPD_DDREFGH_CPU1_LVC1_SCL_4 ; 2 = I3C_SPD_DDREFGH_CPU1_LVC1_SCL
R3904  Q_RES  49.9 1% CHIP  pkg 0402LF  page 111 : 1 = I3C_SPD_DDREFGH_CPU1_LVC1_SCL_5 ; 2 = I3C_SPD_DDREFGH_CPU1_LVC1_SCL
R3905  Q_RES  49.9 1% CHIP  pkg 0402LF  page 112 : 1 = I3C_SPD_DDREFGH_CPU1_LVC1_SCL_6 ; 2 = I3C_SPD_DDREFGH_CPU1_LVC1_SCL
R3906  Q_RES  49.9 1% CHIP  pkg 0402LF  page 113 : 1 = I3C_SPD_DDREFGH_CPU1_LVC1_SCL_7 ; 2 = I3C_SPD_DDREFGH_CPU1_LVC1_SCL
R3907  Q_RES  33K 1% CHIP  pkg 0402LF  page 301 : 1 = PDB_PRSNT_N ; 2 = GND
R3909  Q_RES  33.2 1% CHIP  pkg 0402LF  page 301 : 1 = SMB_SML1_PMBUS_HSC_SCL ; 2 = SMB_SML1_PMBUS_HSC_L_SCL
R3923  Q_RES  63.4K 1% CHIP  pkg 0402LF  page 301 : 1 = P12V_PSU_FUSE ; 2 = PDB_PRSNT_N
R3924  Q_RES  0 5% CHIP  pkg 0402LF  page 301 : 1 = IRQ_SML1_PMBUS_ALERT_N ; 2 = IRQ_SML1_PMBUS_ALERT
R3925  Q_RES  1K 1% CHIP  pkg 0402LF  page 301 : 1 = IRQ_SML1_PMBUS_ALERT ; 2 = P3V3_AUX
R3933  Q_RES  16.9K 1% CHIP  pkg 0402LF  page 301 : 1 = P12V_AUX ; 2 = MB0_P12V_STBY_PWRGD
R3934  Q_RES  22 1% CHIP  pkg 0402LF  page 301 : 1 = HSC_D_OC_R ; 2 = HSC_D_OC
R3936  Q_RES  4.7K 1% CHIP  pkg 0402LF  page 301 : 1 = HSC_VDD ; 2 = HSC_D_OC
R3938  Q_RES  10K 1% CHIP  pkg 0402LF  page 183 : 1 = PU_OC2_USB_N ; 2 = P3V3_AUX
R3939  Q_RES  0 5% EMPTY  pkg 0402LF  page 250 : 1 = P12V_E1S_0_ISENSE_MAM_MAM ; 2 = P12V_E1S_0_ISENSE_MAM
R3940  Q_RES  0 5% EMPTY  pkg 0402LF  page 250 : 1 = P12V_E1S_0_ISENSE_MPS_MAM ; 2 = P12V_E1S_0_ISENSE_MAM
R3941  Q_RES  0 5% EMPTY  pkg 0402LF  page 250 : 1 = P12V_E1S_0_ISENSE_MAM_TIC ; 2 = P12V_E1S_0_ISENSE_TIC
R3942  Q_RES  0 5% CHIP  pkg 0402LF  page 250 : 1 = P12V_E1S_0_ISENSE_MPS_TIC ; 2 = P12V_E1S_0_ISENSE_TIC
R3943  Q_RES  0 5% CHIP  pkg 0402LF  page 193 : 1 = E1S_0_EN ; 2 = P12V_E1S_EN_0_R2
R3946  Q_RES  0 5% EMPTY  pkg 0402LF  page 193 : 1 = E1S_0_EN ; 2 = P3V3_E1S_EN_0_R2
R3948  Q_RES  10K 1% CHIP  pkg 0402LF  page 193 : 1 = P3V3_AUX ; 2 = HP_LVC3_E1S_0_HSC_PWRGD
R3955  Q_RES  0 5% EMPTY  pkg 0402LF  page 193 : 1 = P12V_E1S_IMON_0 ; 2 = P12V_E1S_0_ISENSE_MPS_MAM
R3956  Q_RES  0 5% CHIP  pkg 0402LF  page 193 : 1 = P12V_E1S_IMON_0 ; 2 = P12V_E1S_0_ISENSE_MPS_TIC
R3958  Q_RES  0 5% EMPTY  pkg 0402LF  page 192 : 1 = P12V_E1S_UV_0_R ; 2 = P12V_E1S_UV_0
R3959  Q_RES  0 5% CHIP  pkg 0402LF  page 192 : 1 = P3V3_E1S_UV_0_R ; 2 = P3V3_E1S_UV_0
R3972  Q_RES  0 5% EMPTY  pkg 0402LF  page 192 : 1 = P12V_E1S_PWRGD_0 ; 2 = HP_LVC3_E1S_0_HSC_PWRGD
R3973  Q_RES  0 5% CHIP  pkg 0402LF  page 192 : 1 = P3V3_E1S_PWRGD_0 ; 2 = TP_P3V3_E1S_PWRGD_0
R3974  Q_RES  0 5% EMPTY  pkg 0402LF  page 192 : 1 = P12V_E1S_SENSE_0 ; 2 = P12V_E1S_0_ISENSE_MAM_MAM
R3975  Q_RES  0 5% EMPTY  pkg 0402LF  page 192 : 1 = P12V_E1S_SENSE_0 ; 2 = P12V_E1S_0_ISENSE_MAM_TIC
R3976  Q_RES  100K 1% EMPTY  pkg 0402LF  page 192 : 1 = P3V3_AUX ; 2 = P12V_E1S_FAULT_0
R3977  Q_RES  100K 1% CHIP  pkg 0402LF  page 192 : 1 = P3V3_AUX ; 2 = P3V3_E1S_FAULT_0
R3978  Q_RES  100K 1% EMPTY  pkg 0402LF  page 192 : 1 = P3V3_AUX ; 2 = HP_LVC3_E1S_0_HSC_PWRGD
R3979  Q_RES  100K 1% CHIP  pkg 0402LF  page 192 : 1 = P3V3_AUX ; 2 = TP_P3V3_E1S_PWRGD_0
R3996  Q_RES  0 5% CHIP  pkg 0402LF  page 242 : 1 = VIRTUAL_RESEAT_FPGA_N ; 2 = P12V_SCM_EN
R3997  Q_RES  0 5% EMPTY  pkg 0402LF  page 242 : 1 = P12V_SCM_UV_R ; 2 = P12V_SCM_UV
R3998  Q_RES  0 5% CHIP  pkg 0402LF  page 242 : 1 = P12V_SCM_EN ; 2 = P12V_SCM_EN_R2
R4013  Q_RES  100K 1% EMPTY  pkg 0402LF  page 242 : 1 = P3V3_AUX ; 2 = P12V_SCM_FAULT_R_N
R4015  Q_RES  100K 1% EMPTY  pkg 0402LF  page 242 : 1 = P3V3_AUX ; 2 = HP_LVC3_SCM_HSC_PWRGD
R4016  Q_RES  4.32K 1% CHIP  pkg 0402LF  page 226 : 1 = P3V3 ; 2 = P0V62_CPU0_ERRS_VREF
R4019  Q_RES  1K 1% CHIP  pkg 0402LF  page 226 : 1 = P0V62_CPU0_ERRS_VREF ; 2 = GND
R4021  Q_RES  33.2 1% CHIP  pkg 0402LF  page 226 : 1 = PWRGD_CPUPWRGD_LVC2_R ; 2 = PWRGD_CPUPWRGD_LVC2_R1
R4022  Q_RES  33.2 1% CHIP  pkg 0402LF  page 226 : 1 = H_CPU_RMCA_LVC2_R1_N ; 2 = H_CPU_RMCA_LVC2_R2_N
R4023  Q_RES  33.2 1% CHIP  pkg 0402LF  page 226 : 1 = H_CPU_CATERR_LVC2_R1_N ; 2 = H_CPU_CATERR_LVC2_R2_N
R4029  Q_RES  1K 1% CHIP  pkg 0402LF  page 226 : 1 = PD_CPU0_ERRS_DIR ; 2 = GND
R4036  Q_RES  4.32K 1% CHIP  pkg 0402LF  page 225 : 1 = P3V3_AUX ; 2 = P0V62_CPU0_RST_DDR_VREF
R4037  Q_RES  4.32K 1% CHIP  pkg 0402LF  page 225 : 1 = P3V3_AUX ; 2 = P0V62_CPU1_RST_DDR_VREF
R4038  Q_RES  4.32K 1% CHIP  pkg 0402LF  page 225 : 1 = P3V3 ; 2 = P0V62_CPU0_ERRS_U306_VREF
R4039  Q_RES  1K 1% CHIP  pkg 0402LF  page 225 : 1 = P0V62_CPU0_RST_DDR_VREF ; 2 = GND
R4040  Q_RES  1K 1% CHIP  pkg 0402LF  page 225 : 1 = P0V62_CPU1_RST_DDR_VREF ; 2 = GND
R4041  Q_RES  1K 1% CHIP  pkg 0402LF  page 225 : 1 = P0V62_CPU0_ERRS_U306_VREF ; 2 = GND
R4042  Q_RES  33.2 1% CHIP  pkg 0402LF  page 225 : 1 = RST_CPU0_DRAM_AB_PLD_LVT3_R_N ; 2 = RST_CPU0_DRAM_AB_PLD_LVT3_N
R4043  Q_RES  33.2 1% CHIP  pkg 0402LF  page 225 : 1 = RST_CPU0_DRAM_CD_PLD_LVT3_R_N ; 2 = RST_CPU0_DRAM_CD_PLD_LVT3_N
R4044  Q_RES  33.2 1% CHIP  pkg 0402LF  page 225 : 1 = RST_CPU0_DRAM_EF_PLD_LVT3_R_N ; 2 = RST_CPU0_DRAM_EF_PLD_LVT3_N
R4045  Q_RES  33.2 1% CHIP  pkg 0402LF  page 225 : 1 = RST_CPU0_DRAM_GH_PLD_LVT3_R_N ; 2 = RST_CPU0_DRAM_GH_PLD_LVT3_N
